(kicad_pcb
	(version 20260206)
	(generator "pcbnew")
	(generator_version "10.0")
	(general
		(thickness 1.6)
		(legacy_teardrops no)
	)
	(paper "A4")
	(title_block
		(title "peb — Lightning_PEB_BRD.brd")
		(comment 1 "Lightning (Wiwynn / Facebook NVMe JBOF) / footprints 793-799 of 2563")
	)
	(layers
		(0 "F.Cu" signal "TOP")
		(4 "In1.Cu" signal "L2GND")
		(6 "In2.Cu" signal "L3")
		(8 "In3.Cu" signal "L4VCC")
		(10 "In4.Cu" signal "L5VCC")
		(12 "In5.Cu" signal "L6")
		(14 "In6.Cu" signal "L7GND")
		(2 "B.Cu" signal "BOTTOM")
		(9 "F.Adhes" user "F.Adhesive")
		(11 "B.Adhes" user "B.Adhesive")
		(13 "F.Paste" user "Package Geometry/Pastemask Top")
		(15 "B.Paste" user "Package Geometry/Pastemask Bottom")
		(5 "F.SilkS" user "Ref Des/Silkscreen Top")
		(7 "B.SilkS" user "Ref Des/Silkscreen Bottom")
		(1 "F.Mask" user "Board Geometry/Soldermask Top")
		(3 "B.Mask" user "Board Geometry/Soldermask Bottom")
		(17 "Dwgs.User" user "User.Drawings")
		(19 "Cmts.User" user "User.Comments")
		(21 "Eco1.User" user "User.Eco1")
		(23 "Eco2.User" user "User.Eco2")
		(25 "Edge.Cuts" user "Board Geometry/Outline")
		(27 "Margin" user)
		(31 "F.CrtYd" user "Package Geometry/Place Bound Top")
		(29 "B.CrtYd" user "Package Geometry/Place Bound Bottom")
		(35 "F.Fab" user "Ref Des/Assembly Top")
		(33 "B.Fab" user "Ref Des/Assembly Bottom")
	)
	(footprint ""
		(layer "F.Cu")
		(at 156.2354 -92.329 180)
		(property "Reference" "R712"
			(at 0 0 180)
			(layer "F.SilkS")
			(hide yes)
			(effects
				(font
					(size 1.27 1.27)
				)
			)
		)
		(property "Value" "1MR2F-GP"
			(at 0.064008 -3.993896 180)
			(unlocked yes)
			(layer "F.Fab")
			(hide yes)
			(effects
				(font
					(size 1.016 1.016)
					(thickness 0.1524)
				)
			)
		)
		(property "Device Type" "R402H16"
			(at 0.064008 -5.517896 180)
			(unlocked yes)
			(layer "F.Fab")
			(hide yes)
			(effects
				(font
					(size 1.016 1.016)
					(thickness 0.1524)
				)
			)
		)
		(duplicate_pad_numbers_are_jumpers no)
		(fp_line
			(start 0.508 -0.9398)
			(end -0.508 -0.9398)
			(stroke
				(width 0.1524)
				(type default)
			)
			(layer "F.SilkS")
		)
		(fp_line
			(start -0.508 -0.9398)
			(end -0.508 0.9398)
			(stroke
				(width 0.1524)
				(type default)
			)
			(layer "F.SilkS")
		)
		(fp_rect
			(start -0.508 0.9398)
			(end 0.508 -0.9398)
			(stroke
				(width 0)
				(type default)
			)
			(fill no)
			(layer "F.CrtYd")
		)
		(fp_rect
			(start -0.508 0.9398)
			(end 0.508 -0.9398)
			(stroke
				(width 0)
				(type default)
			)
			(fill no)
			(layer "F.Fab")
		)
		(pad "1" smd custom
			(at 0 -0.4445 180)
			(size 0.1397 0.1397)
			(layers "F.Cu" "F.Mask" "F.Paste")
			(net "XTAL_X2_CLKGEN")
			(options
				(clearance outline)
				(anchor circle)
			)
			(primitives
				(gr_poly
					(pts
						(arc
							(start -0.1778 -0.2794)
							(mid -0.249642 -0.249642)
							(end -0.2794 -0.1778)
						)
						(arc
							(start -0.2794 0.1778)
							(mid -0.249642 0.249642)
							(end -0.1778 0.2794)
						)
						(arc
							(start 0.1778 0.2794)
							(mid 0.249642 0.249642)
							(end 0.2794 0.1778)
						)
						(arc
							(start 0.2794 -0.1778)
							(mid 0.249642 -0.249642)
							(end 0.1778 -0.2794)
						)
					)
					(width 0)
					(fill yes)
				)
			)
		)
		(pad "2" smd custom
			(at 0 0.4445 180)
			(size 0.1397 0.1397)
			(layers "F.Cu" "F.Mask" "F.Paste")
			(net "XTAL_X1")
			(options
				(clearance outline)
				(anchor circle)
			)
			(primitives
				(gr_poly
					(pts
						(arc
							(start -0.1778 -0.2794)
							(mid -0.249642 -0.249642)
							(end -0.2794 -0.1778)
						)
						(arc
							(start -0.2794 0.1778)
							(mid -0.249642 0.249642)
							(end -0.1778 0.2794)
						)
						(arc
							(start 0.1778 0.2794)
							(mid 0.249642 0.249642)
							(end 0.2794 0.1778)
						)
						(arc
							(start 0.2794 -0.1778)
							(mid 0.249642 -0.249642)
							(end 0.1778 -0.2794)
						)
					)
					(width 0)
					(fill yes)
				)
			)
		)
	)
	(footprint ""
		(layer "F.Cu")
		(at 309.992014 -212.420454 180)
		(property "Reference" "C72"
			(at 0 0 180)
			(layer "F.SilkS")
			(hide yes)
			(effects
				(font
					(size 1.27 1.27)
				)
			)
		)
		(property "Value" "SCD22U10V2KX-1GP"
			(at 1.1811 -2.7051 180)
			(unlocked yes)
			(layer "F.Fab")
			(hide yes)
			(effects
				(font
					(size 1.016 1.016)
					(thickness 0.1524)
				)
			)
		)
		(property "Device Type" "C402H22"
			(at 1.1811 -4.2291 180)
			(unlocked yes)
			(layer "F.Fab")
			(hide yes)
			(effects
				(font
					(size 1.016 1.016)
					(thickness 0.1524)
				)
			)
		)
		(duplicate_pad_numbers_are_jumpers no)
		(fp_rect
			(start -0.4318 0.9525)
			(end 0.4318 -0.9525)
			(stroke
				(width 0)
				(type default)
			)
			(fill no)
			(layer "F.CrtYd")
		)
		(fp_rect
			(start -0.4318 0.9525)
			(end 0.4318 -0.9525)
			(stroke
				(width 0)
				(type default)
			)
			(fill no)
			(layer "F.Fab")
		)
		(pad "1" smd custom
			(at 0 -0.4445 180)
			(size 0.1524 0.1524)
			(layers "F.Cu" "F.Mask" "F.Paste")
			(net "PCIE_TX_CAP_P25")
			(options
				(clearance outline)
				(anchor circle)
			)
			(primitives
				(gr_poly
					(pts
						(arc
							(start 0.3048 -0.2032)
							(mid 0.275042 -0.275042)
							(end 0.2032 -0.3048)
						)
						(arc
							(start -0.2032 -0.3048)
							(mid -0.275042 -0.275042)
							(end -0.3048 -0.2032)
						)
						(arc
							(start -0.3048 0.2032)
							(mid -0.275042 0.275042)
							(end -0.2032 0.3048)
						)
						(arc
							(start 0.2032 0.3048)
							(mid 0.275042 0.275042)
							(end 0.3048 0.2032)
						)
					)
					(width 0)
					(fill yes)
				)
			)
		)
		(pad "2" smd custom
			(at 0 0.4445 180)
			(size 0.1524 0.1524)
			(layers "F.Cu" "F.Mask" "F.Paste")
			(net "PCIE_TX_P25")
			(options
				(clearance outline)
				(anchor circle)
			)
			(primitives
				(gr_poly
					(pts
						(arc
							(start 0.3048 -0.2032)
							(mid 0.275042 -0.275042)
							(end 0.2032 -0.3048)
						)
						(arc
							(start -0.2032 -0.3048)
							(mid -0.275042 -0.275042)
							(end -0.3048 -0.2032)
						)
						(arc
							(start -0.3048 0.2032)
							(mid -0.275042 0.275042)
							(end -0.2032 0.3048)
						)
						(arc
							(start 0.2032 0.3048)
							(mid 0.275042 0.275042)
							(end 0.3048 0.2032)
						)
					)
					(width 0)
					(fill yes)
				)
			)
		)
	)
	(footprint ""
		(layer "F.Cu")
		(at 46.9138 -186.5376 180)
		(property "Reference" "R872"
			(at 0 0 180)
			(layer "F.SilkS")
			(hide yes)
			(effects
				(font
					(size 1.27 1.27)
				)
			)
		)
		(property "Value" "10KR2F-2-GP"
			(at 0.064008 -3.993896 180)
			(unlocked yes)
			(layer "F.Fab")
			(hide yes)
			(effects
				(font
					(size 1.016 1.016)
					(thickness 0.1524)
				)
			)
		)
		(property "Device Type" "R402H16"
			(at 0.064008 -5.517896 180)
			(unlocked yes)
			(layer "F.Fab")
			(hide yes)
			(effects
				(font
					(size 1.016 1.016)
					(thickness 0.1524)
				)
			)
		)
		(duplicate_pad_numbers_are_jumpers no)
		(fp_line
			(start 0.508 -0.9398)
			(end -0.508 -0.9398)
			(stroke
				(width 0.1524)
				(type default)
			)
			(layer "F.SilkS")
		)
		(fp_line
			(start -0.508 -0.9398)
			(end -0.508 0.9398)
			(stroke
				(width 0.1524)
				(type default)
			)
			(layer "F.SilkS")
		)
		(fp_rect
			(start -0.508 0.9398)
			(end 0.508 -0.9398)
			(stroke
				(width 0)
				(type default)
			)
			(fill no)
			(layer "F.CrtYd")
		)
		(fp_rect
			(start -0.508 0.9398)
			(end 0.508 -0.9398)
			(stroke
				(width 0)
				(type default)
			)
			(fill no)
			(layer "F.Fab")
		)
		(pad "1" smd custom
			(at 0 -0.4445 180)
			(size 0.1397 0.1397)
			(layers "F.Cu" "F.Mask" "F.Paste")
			(net "P3V3_STBY")
			(options
				(clearance outline)
				(anchor circle)
			)
			(primitives
				(gr_poly
					(pts
						(arc
							(start -0.1778 -0.2794)
							(mid -0.249642 -0.249642)
							(end -0.2794 -0.1778)
						)
						(arc
							(start -0.2794 0.1778)
							(mid -0.249642 0.249642)
							(end -0.1778 0.2794)
						)
						(arc
							(start 0.1778 0.2794)
							(mid 0.249642 0.249642)
							(end 0.2794 0.1778)
						)
						(arc
							(start 0.2794 -0.1778)
							(mid 0.249642 -0.249642)
							(end 0.1778 -0.2794)
						)
					)
					(width 0)
					(fill yes)
				)
			)
		)
		(pad "2" smd custom
			(at 0 0.4445 180)
			(size 0.1397 0.1397)
			(layers "F.Cu" "F.Mask" "F.Paste")
			(net "I2C9_BUFF_EN")
			(options
				(clearance outline)
				(anchor circle)
			)
			(primitives
				(gr_poly
					(pts
						(arc
							(start -0.1778 -0.2794)
							(mid -0.249642 -0.249642)
							(end -0.2794 -0.1778)
						)
						(arc
							(start -0.2794 0.1778)
							(mid -0.249642 0.249642)
							(end -0.1778 0.2794)
						)
						(arc
							(start 0.1778 0.2794)
							(mid 0.249642 0.249642)
							(end 0.2794 0.1778)
						)
						(arc
							(start 0.2794 -0.1778)
							(mid 0.249642 -0.249642)
							(end 0.1778 -0.2794)
						)
					)
					(width 0)
					(fill yes)
				)
			)
		)
	)
	(footprint ""
		(layer "F.Cu")
		(at 166.116 -88.5444 90)
		(property "Reference" "R3104"
			(at 0 0 90)
			(layer "F.SilkS")
			(hide yes)
			(effects
				(font
					(size 1.27 1.27)
				)
			)
		)
		(property "Value" "27R2F-GP"
			(at 0.064008 -3.993896 90)
			(unlocked yes)
			(layer "F.Fab")
			(hide yes)
			(effects
				(font
					(size 1.016 1.016)
					(thickness 0.1524)
				)
			)
		)
		(property "Device Type" "R402H16"
			(at 0.064008 -5.517896 90)
			(unlocked yes)
			(layer "F.Fab")
			(hide yes)
			(effects
				(font
					(size 1.016 1.016)
					(thickness 0.1524)
				)
			)
		)
		(duplicate_pad_numbers_are_jumpers no)
		(fp_line
			(start 0.508 -0.9398)
			(end -0.508 -0.9398)
			(stroke
				(width 0.1524)
				(type default)
			)
			(layer "F.SilkS")
		)
		(fp_line
			(start -0.508 -0.9398)
			(end -0.508 0.9398)
			(stroke
				(width 0.1524)
				(type default)
			)
			(layer "F.SilkS")
		)
		(fp_rect
			(start -0.508 0.9398)
			(end 0.508 -0.9398)
			(stroke
				(width 0)
				(type default)
			)
			(fill no)
			(layer "F.CrtYd")
		)
		(fp_rect
			(start -0.508 0.9398)
			(end 0.508 -0.9398)
			(stroke
				(width 0)
				(type default)
			)
			(fill no)
			(layer "F.Fab")
		)
		(pad "1" smd custom
			(at 0 -0.4445 90)
			(size 0.1397 0.1397)
			(layers "F.Cu" "F.Mask" "F.Paste")
			(net "CLKGEN_P1_R")
			(options
				(clearance outline)
				(anchor circle)
			)
			(primitives
				(gr_poly
					(pts
						(arc
							(start -0.1778 -0.2794)
							(mid -0.249642 -0.249642)
							(end -0.2794 -0.1778)
						)
						(arc
							(start -0.2794 0.1778)
							(mid -0.249642 0.249642)
							(end -0.1778 0.2794)
						)
						(arc
							(start 0.1778 0.2794)
							(mid 0.249642 0.249642)
							(end 0.2794 0.1778)
						)
						(arc
							(start 0.2794 -0.1778)
							(mid 0.249642 -0.249642)
							(end 0.1778 -0.2794)
						)
					)
					(width 0)
					(fill yes)
				)
			)
		)
		(pad "2" smd custom
			(at 0 0.4445 90)
			(size 0.1397 0.1397)
			(layers "F.Cu" "F.Mask" "F.Paste")
			(net "I210_REFCLK_D_P")
			(options
				(clearance outline)
				(anchor circle)
			)
			(primitives
				(gr_poly
					(pts
						(arc
							(start -0.1778 -0.2794)
							(mid -0.249642 -0.249642)
							(end -0.2794 -0.1778)
						)
						(arc
							(start -0.2794 0.1778)
							(mid -0.249642 0.249642)
							(end -0.1778 0.2794)
						)
						(arc
							(start 0.1778 0.2794)
							(mid 0.249642 0.249642)
							(end 0.2794 0.1778)
						)
						(arc
							(start 0.2794 -0.1778)
							(mid 0.249642 -0.249642)
							(end 0.1778 -0.2794)
						)
					)
					(width 0)
					(fill yes)
				)
			)
		)
	)
	(footprint ""
		(layer "F.Cu")
		(at 21.336 -145.415 180)
		(property "Reference" "C195"
			(at 0 0 180)
			(layer "F.SilkS")
			(hide yes)
			(effects
				(font
					(size 1.27 1.27)
				)
			)
		)
		(property "Value" "SCD1U16V2KX-3GP"
			(at 1.1811 -2.7051 180)
			(unlocked yes)
			(layer "F.Fab")
			(hide yes)
			(effects
				(font
					(size 1.016 1.016)
					(thickness 0.1524)
				)
			)
		)
		(property "Device Type" "C402H22"
			(at 1.1811 -4.2291 180)
			(unlocked yes)
			(layer "F.Fab")
			(hide yes)
			(effects
				(font
					(size 1.016 1.016)
					(thickness 0.1524)
				)
			)
		)
		(duplicate_pad_numbers_are_jumpers no)
		(fp_rect
			(start -0.4318 0.9525)
			(end 0.4318 -0.9525)
			(stroke
				(width 0)
				(type default)
			)
			(fill no)
			(layer "F.CrtYd")
		)
		(fp_rect
			(start -0.4318 0.9525)
			(end 0.4318 -0.9525)
			(stroke
				(width 0)
				(type default)
			)
			(fill no)
			(layer "F.Fab")
		)
		(pad "1" smd custom
			(at 0 -0.4445 180)
			(size 0.1524 0.1524)
			(layers "F.Cu" "F.Mask" "F.Paste")
			(net "MPLLAV33")
			(options
				(clearance outline)
				(anchor circle)
			)
			(primitives
				(gr_poly
					(pts
						(arc
							(start 0.3048 -0.2032)
							(mid 0.275042 -0.275042)
							(end 0.2032 -0.3048)
						)
						(arc
							(start -0.2032 -0.3048)
							(mid -0.275042 -0.275042)
							(end -0.3048 -0.2032)
						)
						(arc
							(start -0.3048 0.2032)
							(mid -0.275042 0.275042)
							(end -0.2032 0.3048)
						)
						(arc
							(start 0.2032 0.3048)
							(mid 0.275042 0.275042)
							(end 0.3048 0.2032)
						)
					)
					(width 0)
					(fill yes)
				)
			)
		)
		(pad "2" smd custom
			(at 0 0.4445 180)
			(size 0.1524 0.1524)
			(layers "F.Cu" "F.Mask" "F.Paste")
			(net "GND")
			(options
				(clearance outline)
				(anchor circle)
			)
			(primitives
				(gr_poly
					(pts
						(arc
							(start 0.3048 -0.2032)
							(mid 0.275042 -0.275042)
							(end 0.2032 -0.3048)
						)
						(arc
							(start -0.2032 -0.3048)
							(mid -0.275042 -0.275042)
							(end -0.3048 -0.2032)
						)
						(arc
							(start -0.3048 0.2032)
							(mid -0.275042 0.275042)
							(end -0.2032 0.3048)
						)
						(arc
							(start 0.2032 0.3048)
							(mid 0.275042 0.275042)
							(end 0.3048 0.2032)
						)
					)
					(width 0)
					(fill yes)
				)
			)
		)
	)
	(footprint ""
		(layer "F.Cu")
		(at 270.599916 -17.500092 90)
		(property "Reference" "LED22"
			(at 0 0 90)
			(layer "F.SilkS")
			(hide yes)
			(effects
				(font
					(size 1.27 1.27)
				)
			)
		)
		(property "Value" "LED-YG-51-GP"
			(at -2.6924 -1.4224 90)
			(unlocked yes)
			(layer "F.Fab")
			(hide yes)
			(effects
				(font
					(size 1.016 1.016)
					(thickness 0.1524)
				)
			)
		)
		(property "Device Type" "LED1608AKH40"
			(at -2.6924 -2.9464 90)
			(unlocked yes)
			(layer "F.Fab")
			(hide yes)
			(effects
				(font
					(size 1.016 1.016)
					(thickness 0.1524)
				)
			)
		)
		(duplicate_pad_numbers_are_jumpers no)
		(fp_line
			(start 0.6604 -1.3716)
			(end 0.6604 1.3716)
			(stroke
				(width 0.1524)
				(type default)
			)
			(layer "F.SilkS")
		)
		(fp_line
			(start -0.6604 -1.3716)
			(end 0.6604 -1.3716)
			(stroke
				(width 0.1524)
				(type default)
			)
			(layer "F.SilkS")
		)
		(fp_line
			(start 0.6604 1.3716)
			(end -0.6604 1.3716)
			(stroke
				(width 0.1524)
				(type default)
			)
			(layer "F.SilkS")
		)
		(fp_line
			(start -0.6604 1.3716)
			(end -0.6604 -1.3716)
			(stroke
				(width 0.1524)
				(type default)
			)
			(layer "F.SilkS")
		)
		(fp_line
			(start -0.5969 1.5494)
			(end 0.5842 1.5494)
			(stroke
				(width 0.508)
				(type default)
			)
			(layer "F.SilkS")
		)
		(fp_line
			(start 0.7493 1.651)
			(end 0.7493 1.1811)
			(stroke
				(width 0.3302)
				(type default)
			)
			(layer "F.SilkS")
		)
		(fp_line
			(start -0.7493 1.651)
			(end -0.7493 1.1811)
			(stroke
				(width 0.3302)
				(type default)
			)
			(layer "F.SilkS")
		)
		(fp_rect
			(start -0.6223 1.3335)
			(end 0.6223 -1.3335)
			(stroke
				(width 0)
				(type default)
			)
			(fill no)
			(layer "F.CrtYd")
		)
		(fp_rect
			(start -0.6223 1.3335)
			(end 0.6223 -1.3335)
			(stroke
				(width 0)
				(type default)
			)
			(fill no)
			(layer "F.Fab")
		)
		(pad "A" smd custom
			(at 0 -0.762 90)
			(size 0.2159 0.2159)
			(layers "F.Cu" "F.Mask" "F.Paste")
			(net "LED_R_13")
			(options
				(clearance outline)
				(anchor circle)
			)
			(primitives
				(gr_poly
					(pts
						(arc
							(start -0.3302 -0.4318)
							(mid -0.402042 -0.402042)
							(end -0.4318 -0.3302)
						)
						(arc
							(start -0.4318 0.3302)
							(mid -0.402042 0.402042)
							(end -0.3302 0.4318)
						)
						(arc
							(start 0.3302 0.4318)
							(mid 0.402042 0.402042)
							(end 0.4318 0.3302)
						)
						(arc
							(start 0.4318 -0.3302)
							(mid 0.402042 -0.402042)
							(end 0.3302 -0.4318)
						)
					)
					(width 0)
					(fill yes)
				)
			)
		)
		(pad "K" smd custom
			(at 0 0.762 90)
			(size 0.2159 0.2159)
			(layers "F.Cu" "F.Mask" "F.Paste")
			(net "LED_Q_13")
			(options
				(clearance outline)
				(anchor circle)
			)
			(primitives
				(gr_poly
					(pts
						(arc
							(start -0.3302 -0.4318)
							(mid -0.402042 -0.402042)
							(end -0.4318 -0.3302)
						)
						(arc
							(start -0.4318 0.3302)
							(mid -0.402042 0.402042)
							(end -0.3302 0.4318)
						)
						(arc
							(start 0.3302 0.4318)
							(mid 0.402042 0.402042)
							(end 0.4318 0.3302)
						)
						(arc
							(start 0.4318 -0.3302)
							(mid 0.402042 -0.402042)
							(end 0.3302 -0.4318)
						)
					)
					(width 0)
					(fill yes)
				)
			)
		)
	)
	(footprint ""
		(layer "F.Cu")
		(at 228.732588 -3.801364 180)
		(property "Reference" "C249"
			(at 0 0 180)
			(layer "F.SilkS")
			(hide yes)
			(effects
				(font
					(size 1.27 1.27)
				)
			)
		)
		(property "Value" "SCD1U16V2KX-3GP"
			(at 1.1811 -2.7051 180)
			(unlocked yes)
			(layer "F.Fab")
			(hide yes)
			(effects
				(font
					(size 1.016 1.016)
					(thickness 0.1524)
				)
			)
		)
		(property "Device Type" "C402H22"
			(at 1.1811 -4.2291 180)
			(unlocked yes)
			(layer "F.Fab")
			(hide yes)
			(effects
				(font
					(size 1.016 1.016)
					(thickness 0.1524)
				)
			)
		)
		(duplicate_pad_numbers_are_jumpers no)
		(fp_rect
			(start -0.4318 0.9525)
			(end 0.4318 -0.9525)
			(stroke
				(width 0)
				(type default)
			)
			(fill no)
			(layer "F.CrtYd")
		)
		(fp_rect
			(start -0.4318 0.9525)
			(end 0.4318 -0.9525)
			(stroke
				(width 0)
				(type default)
			)
			(fill no)
			(layer "F.Fab")
		)
		(pad "1" smd custom
			(at 0 -0.4445 180)
			(size 0.1524 0.1524)
			(layers "F.Cu" "F.Mask" "F.Paste")
			(net "P5V_STBY")
			(options
				(clearance outline)
				(anchor circle)
			)
			(primitives
				(gr_poly
					(pts
						(arc
							(start 0.3048 -0.2032)
							(mid 0.275042 -0.275042)
							(end 0.2032 -0.3048)
						)
						(arc
							(start -0.2032 -0.3048)
							(mid -0.275042 -0.275042)
							(end -0.3048 -0.2032)
						)
						(arc
							(start -0.3048 0.2032)
							(mid -0.275042 0.275042)
							(end -0.2032 0.3048)
						)
						(arc
							(start 0.2032 0.3048)
							(mid 0.275042 0.275042)
							(end 0.3048 0.2032)
						)
					)
					(width 0)
					(fill yes)
				)
			)
		)
		(pad "2" smd custom
			(at 0 0.4445 180)
			(size 0.1524 0.1524)
			(layers "F.Cu" "F.Mask" "F.Paste")
			(net "GND")
			(options
				(clearance outline)
				(anchor circle)
			)
			(primitives
				(gr_poly
					(pts
						(arc
							(start 0.3048 -0.2032)
							(mid 0.275042 -0.275042)
							(end 0.2032 -0.3048)
						)
						(arc
							(start -0.2032 -0.3048)
							(mid -0.275042 -0.275042)
							(end -0.3048 -0.2032)
						)
						(arc
							(start -0.3048 0.2032)
							(mid -0.275042 0.275042)
							(end -0.2032 0.3048)
						)
						(arc
							(start 0.2032 0.3048)
							(mid 0.275042 0.275042)
							(end 0.3048 0.2032)
						)
					)
					(width 0)
					(fill yes)
				)
			)
		)
	)
)
